# S9S_MB_2U (Grand Teton) — schematic netlist excerpt (pin names and nets, part order shuffled) for the footprints in the layout excerpt that follows; sources: Cadence DE-HDL packaged netlist, KiCad conversion of 03242023_DA0F0TMBIJ0_F0T_Motherboard_J_brd_V01_OCP.brd

R1935  Q_RES  33.2 1% CHIP  pkg 0402LF  page 45 : A = SMB_S3M_CPU1_PIROM_3V3AUX_SDA ; B = SMB_S3M_CPU1_PIROM_3V3AUX_SDA_1
C111  Q_CAP  0.047UF 25V 10% X7R  pkg C0402  page 210 : A = P3V3_AUX_CLK_GEN_VDDXTAL_CK440 ; B = GND
PC288_P0_4  Q_CAP  22UF 4V 20% X6S  pkg C0805  page 268 : A = PVCCIN_CPU0 ; B = GND

(kicad_pcb
	(version 20260206)
	(generator "pcbnew")
	(generator_version "10.0")
	(general
		(thickness 1.6)
		(legacy_teardrops no)
	)
	(paper "A4")
	(title_block
		(title "03242023_DA0F0TMBIJ0_F0T_Motherboard_J_brd_V01_OCP.brd")
		(comment 1 "Grand Teton / footprints 5008-5010 of 6105")
	)
	(layers
		(0 "F.Cu" signal "TOP")
		(4 "In1.Cu" signal "GND")
		(6 "In2.Cu" signal "IN1")
		(8 "In3.Cu" signal "GND1")
		(10 "In4.Cu" signal "IN2")
		(12 "In5.Cu" signal "GND2")
		(14 "In6.Cu" signal "IN3")
		(16 "In7.Cu" signal "GND3")
		(18 "In8.Cu" signal "VCC")
		(20 "In9.Cu" signal "VCC1")
		(22 "In10.Cu" signal "GND4")
		(24 "In11.Cu" signal "IN4")
		(26 "In12.Cu" signal "GND5")
		(28 "In13.Cu" signal "IN5")
		(30 "In14.Cu" signal "GND6")
		(32 "In15.Cu" signal "IN6")
		(34 "In16.Cu" signal "GND7")
		(2 "B.Cu" signal "BOTTOM")
		(9 "F.Adhes" user "F.Adhesive")
		(11 "B.Adhes" user "B.Adhesive")
		(13 "F.Paste" user "Package Geometry/Pastemask Top")
		(15 "B.Paste" user "Package Geometry/Pastemask Bottom")
		(5 "F.SilkS" user "Ref Des/Silkscreen Top")
		(7 "B.SilkS" user "Ref Des/Silkscreen Bottom")
		(1 "F.Mask" user "Board Geometry/Soldermask Top")
		(3 "B.Mask" user "Board Geometry/Soldermask Bottom")
		(17 "Dwgs.User" user "User.Drawings")
		(19 "Cmts.User" user "User.Comments")
		(21 "Eco1.User" user "User.Eco1")
		(23 "Eco2.User" user "User.Eco2")
		(25 "Edge.Cuts" user "Board Geometry/Outline")
		(27 "Margin" user)
		(31 "F.CrtYd" user "Package Geometry/Place Bound Top")
		(29 "B.CrtYd" user "Package Geometry/Place Bound Bottom")
		(35 "F.Fab" user "Ref Des/Assembly Top")
		(33 "B.Fab" user "Ref Des/Assembly Bottom")
	)
	(footprint ""
		(layer "B.Cu")
		(at 252.222 -97.373948 180)
		(property "Reference" "C111"
			(at 0 0 0)
			(layer "B.SilkS")
			(hide yes)
			(effects
				(font
					(size 1.27 1.27)
				)
				(justify mirror)
			)
		)
		(property "Value" ""
			(at 0 0 0)
			(layer "B.Fab")
			(effects
				(font
					(size 1.27 1.27)
				)
				(justify mirror)
			)
		)
		(duplicate_pad_numbers_are_jumpers no)
		(fp_line
			(start 0.7874 0.4064)
			(end 0.7874 -0.4064)
			(stroke
				(width 0.1524)
				(type default)
			)
			(layer "B.SilkS")
		)
		(fp_line
			(start 0.7874 -0.4064)
			(end -0.7874 -0.4064)
			(stroke
				(width 0.1524)
				(type default)
			)
			(layer "B.SilkS")
		)
		(fp_line
			(start -0.7874 0.4064)
			(end 0.7874 0.4064)
			(stroke
				(width 0.1524)
				(type default)
			)
			(layer "B.SilkS")
		)
		(fp_line
			(start -0.7874 -0.4064)
			(end -0.7874 0.4064)
			(stroke
				(width 0.1524)
				(type default)
			)
			(layer "B.SilkS")
		)
		(fp_line
			(start 0.67945 0.3048)
			(end 0.67945 -0.305054)
			(stroke
				(width 0.1)
				(type default)
			)
			(layer "B.Fab")
		)
		(fp_line
			(start 0.67945 -0.305054)
			(end 0.12065 -0.305054)
			(stroke
				(width 0.1)
				(type default)
			)
			(layer "B.Fab")
		)
		(fp_line
			(start 0.12065 0.3048)
			(end 0.67945 0.3048)
			(stroke
				(width 0.1)
				(type default)
			)
			(layer "B.Fab")
		)
		(fp_line
			(start 0.12065 0.2794)
			(end 0.12065 0.3048)
			(stroke
				(width 0.1)
				(type default)
			)
			(layer "B.Fab")
		)
		(fp_line
			(start 0.12065 -0.2794)
			(end -0.12065 -0.2794)
			(stroke
				(width 0.1)
				(type default)
			)
			(layer "B.Fab")
		)
		(fp_line
			(start 0.12065 -0.305054)
			(end 0.12065 -0.2794)
			(stroke
				(width 0.1)
				(type default)
			)
			(layer "B.Fab")
		)
		(fp_line
			(start -0.120396 0.3048)
			(end -0.120396 0.2794)
			(stroke
				(width 0.1)
				(type default)
			)
			(layer "B.Fab")
		)
		(fp_line
			(start -0.120396 0.2794)
			(end 0.12065 0.2794)
			(stroke
				(width 0.1)
				(type default)
			)
			(layer "B.Fab")
		)
		(fp_line
			(start -0.12065 -0.2794)
			(end -0.12065 -0.3048)
			(stroke
				(width 0.1)
				(type default)
			)
			(layer "B.Fab")
		)
		(fp_line
			(start -0.12065 -0.3048)
			(end -0.67945 -0.3048)
			(stroke
				(width 0.1)
				(type default)
			)
			(layer "B.Fab")
		)
		(fp_line
			(start -0.67945 0.3048)
			(end -0.120396 0.3048)
			(stroke
				(width 0.1)
				(type default)
			)
			(layer "B.Fab")
		)
		(fp_line
			(start -0.67945 -0.3048)
			(end -0.67945 0.3048)
			(stroke
				(width 0.1)
				(type default)
			)
			(layer "B.Fab")
		)
		(pad "1" smd circle
			(at 0.40005 0)
			(size 0 0)
			(layers "B.Cu" "B.Mask" "B.Paste")
			(net "P3V3_AUX_CLK_GEN_VDDXTAL_CK440")
		)
		(pad "2" smd circle
			(at -0.40005 0)
			(size 0 0)
			(layers "B.Cu" "B.Mask" "B.Paste")
			(net "GND")
		)
	)
	(footprint ""
		(layer "B.Cu")
		(at 370.901468 -324.911466 -90)
		(property "Reference" "PC288_P0_4"
			(at 0 0 90)
			(layer "B.SilkS")
			(hide yes)
			(effects
				(font
					(size 1.27 1.27)
				)
				(justify mirror)
			)
		)
		(property "Value" ""
			(at 0 0 90)
			(layer "B.Fab")
			(effects
				(font
					(size 1.27 1.27)
				)
				(justify mirror)
			)
		)
		(duplicate_pad_numbers_are_jumpers no)
		(fp_line
			(start -1.524 0.762)
			(end 1.524 0.762)
			(stroke
				(width 0.1524)
				(type default)
			)
			(layer "B.SilkS")
		)
		(fp_line
			(start 1.524 0.762)
			(end 1.524 -0.762)
			(stroke
				(width 0.1524)
				(type default)
			)
			(layer "B.SilkS")
		)
		(fp_line
			(start -1.524 -0.762)
			(end -1.524 0.762)
			(stroke
				(width 0.1524)
				(type default)
			)
			(layer "B.SilkS")
		)
		(fp_line
			(start 1.524 -0.762)
			(end -1.524 -0.762)
			(stroke
				(width 0.1524)
				(type default)
			)
			(layer "B.SilkS")
		)
		(fp_line
			(start -1.1049 0.724916)
			(end -1.1049 -0.724916)
			(stroke
				(width 0.1)
				(type default)
			)
			(layer "B.Fab")
		)
		(fp_line
			(start 1.1049 0.724916)
			(end -1.1049 0.724916)
			(stroke
				(width 0.1)
				(type default)
			)
			(layer "B.Fab")
		)
		(fp_line
			(start -1.1049 -0.724916)
			(end 1.1049 -0.724916)
			(stroke
				(width 0.1)
				(type default)
			)
			(layer "B.Fab")
		)
		(fp_line
			(start 1.1049 -0.724916)
			(end 1.1049 0.724916)
			(stroke
				(width 0.1)
				(type default)
			)
			(layer "B.Fab")
		)
		(pad "1" smd rect
			(at 0.889 0 270)
			(size 1.016 1.27)
			(layers "B.Cu" "B.Mask" "B.Paste")
			(net "PVCCIN_CPU0")
		)
		(pad "2" smd rect
			(at -0.889 0 270)
			(size 1.016 1.27)
			(layers "B.Cu" "B.Mask" "B.Paste")
			(net "GND")
		)
	)
	(footprint ""
		(layer "B.Cu")
		(at 178.61788 -330.495148)
		(property "Reference" "R1935"
			(at 0 0 0)
			(layer "B.SilkS")
			(hide yes)
			(effects
				(font
					(size 1.27 1.27)
				)
				(justify mirror)
			)
		)
		(property "Value" ""
			(at 0 0 0)
			(layer "B.Fab")
			(effects
				(font
					(size 1.27 1.27)
				)
				(justify mirror)
			)
		)
		(duplicate_pad_numbers_are_jumpers no)
		(fp_line
			(start -0.7874 -0.4064)
			(end -0.7874 0.4064)
			(stroke
				(width 0.1524)
				(type default)
			)
			(layer "B.SilkS")
		)
		(fp_line
			(start -0.7874 0.4064)
			(end 0.7874 0.4064)
			(stroke
				(width 0.1524)
				(type default)
			)
			(layer "B.SilkS")
		)
		(fp_line
			(start 0.7874 -0.4064)
			(end -0.7874 -0.4064)
			(stroke
				(width 0.1524)
				(type default)
			)
			(layer "B.SilkS")
		)
		(fp_line
			(start 0.7874 0.4064)
			(end 0.7874 -0.4064)
			(stroke
				(width 0.1524)
				(type default)
			)
			(layer "B.SilkS")
		)
		(fp_line
			(start -0.67945 -0.3048)
			(end -0.67945 0.3048)
			(stroke
				(width 0.1)
				(type default)
			)
			(layer "B.Fab")
		)
		(fp_line
			(start -0.67945 0.3048)
			(end -0.120396 0.3048)
			(stroke
				(width 0.1)
				(type default)
			)
			(layer "B.Fab")
		)
		(fp_line
			(start -0.12065 -0.3048)
			(end -0.67945 -0.3048)
			(stroke
				(width 0.1)
				(type default)
			)
			(layer "B.Fab")
		)
		(fp_line
			(start -0.12065 -0.2794)
			(end -0.12065 -0.3048)
			(stroke
				(width 0.1)
				(type default)
			)
			(layer "B.Fab")
		)
		(fp_line
			(start -0.120396 0.2794)
			(end 0.12065 0.2794)
			(stroke
				(width 0.1)
				(type default)
			)
			(layer "B.Fab")
		)
		(fp_line
			(start -0.120396 0.3048)
			(end -0.120396 0.2794)
			(stroke
				(width 0.1)
				(type default)
			)
			(layer "B.Fab")
		)
		(fp_line
			(start 0.12065 -0.305054)
			(end 0.12065 -0.2794)
			(stroke
				(width 0.1)
				(type default)
			)
			(layer "B.Fab")
		)
		(fp_line
			(start 0.12065 -0.2794)
			(end -0.12065 -0.2794)
			(stroke
				(width 0.1)
				(type default)
			)
			(layer "B.Fab")
		)
		(fp_line
			(start 0.12065 0.2794)
			(end 0.12065 0.3048)
			(stroke
				(width 0.1)
				(type default)
			)
			(layer "B.Fab")
		)
		(fp_line
			(start 0.12065 0.3048)
			(end 0.67945 0.3048)
			(stroke
				(width 0.1)
				(type default)
			)
			(layer "B.Fab")
		)
		(fp_line
			(start 0.67945 -0.305054)
			(end 0.12065 -0.305054)
			(stroke
				(width 0.1)
				(type default)
			)
			(layer "B.Fab")
		)
		(fp_line
			(start 0.67945 0.3048)
			(end 0.67945 -0.305054)
			(stroke
				(width 0.1)
				(type default)
			)
			(layer "B.Fab")
		)
		(pad "1" smd circle
			(at 0.40005 0 180)
			(size 0 0)
			(layers "B.Cu" "B.Mask" "B.Paste")
			(net "SMB_S3M_CPU1_PIROM_3V3AUX_SDA")
		)
		(pad "2" smd circle
			(at -0.40005 0 180)
			(size 0 0)
			(layers "B.Cu" "B.Mask" "B.Paste")
			(net "SMB_S3M_CPU1_PIROM_3V3AUX_SDA_1")
		)
	)
)
